#ISCELL
  mstr_symbols bom_note *
  *
#ISCELL
  mstr_symbols intel_corp_bpage *
  *
#ISCELL
  mstr_symbols gnd *
  page80_i1
#ISCELL
  mstr_standard offpage *
  page80_i10
#ISCELL
  mstr_standard tap *
  page80_i100
#CELL
  mstr_sconn sconn288_h44441003 *
  page80_i101
#ISCELL
  mstr_standard tap *
  page80_i102
#ISCELL
  mstr_standard tap *
  page80_i103
#ISCELL
  mstr_standard tap *
  page80_i104
#ISCELL
  mstr_standard tap *
  page80_i105
#ISCELL
  mstr_standard tap *
  page80_i106
#ISCELL
  mstr_standard tap *
  page80_i107
#ISCELL
  mstr_standard tap *
  page80_i108
#ISCELL
  mstr_standard tap *
  page80_i109
#ISCELL
  mstr_standard offpage *
  page80_i11
#ISCELL
  mstr_standard tap *
  page80_i110
#ISCELL
  mstr_standard tap *
  page80_i111
#ISCELL
  mstr_standard tap *
  page80_i112
#ISCELL
  mstr_standard tap *
  page80_i113
#ISCELL
  mstr_standard tap *
  page80_i114
#ISCELL
  mstr_standard tap *
  page80_i115
#ISCELL
  mstr_standard tap *
  page80_i116
#ISCELL
  mstr_standard tap *
  page80_i117
#ISCELL
  mstr_standard tap *
  page80_i118
#ISCELL
  mstr_standard tap *
  page80_i119
#ISCELL
  mstr_standard offpage *
  page80_i12
#ISCELL
  mstr_standard tap *
  page80_i120
#ISCELL
  mstr_standard tap *
  page80_i121
#ISCELL
  mstr_standard tap *
  page80_i122
#ISCELL
  mstr_standard tap *
  page80_i123
#ISCELL
  mstr_standard tap *
  page80_i124
#ISCELL
  mstr_standard tap *
  page80_i125
#ISCELL
  mstr_standard tap *
  page80_i126
#ISCELL
  mstr_standard tap *
  page80_i127
#ISCELL
  mstr_standard tap *
  page80_i128
#ISCELL
  mstr_standard tap *
  page80_i129
#ISCELL
  mstr_standard offpage *
  page80_i13
#ISCELL
  mstr_standard tap *
  page80_i130
#ISCELL
  mstr_standard tap *
  page80_i131
#ISCELL
  mstr_standard tap *
  page80_i132
#ISCELL
  mstr_standard tap *
  page80_i133
#ISCELL
  mstr_standard tap *
  page80_i134
#ISCELL
  mstr_standard tap *
  page80_i135
#ISCELL
  mstr_standard offpage *
  page80_i136
#ISCELL
  mstr_symbols gnd *
  page80_i137
#CELL
  mstr_sconn sconn288_h44441003 *
  page80_i138
#ISCELL
  mstr_standard offpage *
  page80_i14
#ISCELL
  mstr_standard tap *
  page80_i142
#ISCELL
  mstr_standard tap *
  page80_i143
#ISCELL
  mstr_standard tap *
  page80_i144
#ISCELL
  mstr_standard tap *
  page80_i145
#ISCELL
  mstr_standard tap *
  page80_i146
#ISCELL
  mstr_standard tap *
  page80_i147
#ISCELL
  mstr_standard tap *
  page80_i148
#ISCELL
  mstr_standard tap *
  page80_i149
#ISCELL
  mstr_standard offpage *
  page80_i15
#ISCELL
  mstr_standard tap *
  page80_i150
#ISCELL
  mstr_standard tap *
  page80_i151
#ISCELL
  mstr_standard tap *
  page80_i152
#ISCELL
  mstr_standard tap *
  page80_i153
#ISCELL
  mstr_standard tap *
  page80_i154
#ISCELL
  mstr_standard tap *
  page80_i155
#ISCELL
  mstr_symbols gnd *
  page80_i156
#ISCELL
  mstr_standard tap *
  page80_i157
#ISCELL
  mstr_standard tap *
  page80_i158
#ISCELL
  mstr_standard tap *
  page80_i159
#ISCELL
  mstr_standard offpage *
  page80_i16
#ISCELL
  mstr_standard tap *
  page80_i160
#ISCELL
  mstr_standard tap *
  page80_i161
#ISCELL
  mstr_standard tap *
  page80_i162
#ISCELL
  mstr_standard tap *
  page80_i163
#ISCELL
  mstr_standard tap *
  page80_i164
#ISCELL
  mstr_standard tap *
  page80_i165
#ISCELL
  mstr_standard tap *
  page80_i166
#ISCELL
  mstr_standard tap *
  page80_i167
#ISCELL
  mstr_standard tap *
  page80_i168
#ISCELL
  mstr_standard tap *
  page80_i169
#ISCELL
  mstr_standard offpage *
  page80_i17
#ISCELL
  mstr_standard tap *
  page80_i170
#ISCELL
  mstr_standard tap *
  page80_i171
#ISCELL
  mstr_standard tap *
  page80_i172
#ISCELL
  mstr_standard tap *
  page80_i173
#ISCELL
  mstr_standard tap *
  page80_i174
#ISCELL
  mstr_standard tap *
  page80_i175
#ISCELL
  mstr_standard tap *
  page80_i176
#ISCELL
  mstr_standard tap *
  page80_i177
#ISCELL
  mstr_standard tap *
  page80_i178
#ISCELL
  mstr_standard offpage *
  page80_i179
#ISCELL
  mstr_standard offpage *
  page80_i18
#ISCELL
  mstr_standard offpage *
  page80_i180
#ISCELL
  mstr_symbols p12v_nvdimm_ghj *
  page80_i181
#ISCELL
  mstr_standard offpage *
  page80_i19
#ISCELL
  mstr_standard offpage *
  page80_i2
#ISCELL
  mstr_standard offpage *
  page80_i20
#ISCELL
  mstr_standard offpage *
  page80_i21
#ISCELL
  mstr_standard offpage *
  page80_i22
#ISCELL
  mstr_standard offpage *
  page80_i23
#CELL
  mstr_sconn sconn288_h44441003 *
  page80_i24
#ISCELL
  mstr_standard tap *
  page80_i25
#ISCELL
  mstr_standard tap *
  page80_i26
#ISCELL
  mstr_standard tap *
  page80_i27
#ISCELL
  mstr_standard tap *
  page80_i28
#ISCELL
  mstr_standard tap *
  page80_i29
#CELL
  dev_discrete cap_a *
  page80_i3
#ISCELL
  mstr_standard tap *
  page80_i30
#ISCELL
  mstr_standard tap *
  page80_i31
#ISCELL
  mstr_standard tap *
  page80_i32
#ISCELL
  mstr_standard tap *
  page80_i33
#ISCELL
  mstr_standard tap *
  page80_i34
#ISCELL
  mstr_standard tap *
  page80_i35
#ISCELL
  mstr_standard tap *
  page80_i36
#ISCELL
  mstr_standard tap *
  page80_i37
#ISCELL
  mstr_standard tap *
  page80_i38
#ISCELL
  mstr_standard tap *
  page80_i39
#ISCELL
  mstr_symbols gnd *
  page80_i4
#ISCELL
  mstr_standard tap *
  page80_i40
#ISCELL
  mstr_standard tap *
  page80_i41
#ISCELL
  mstr_standard tap *
  page80_i42
#ISCELL
  mstr_standard tap *
  page80_i43
#ISCELL
  mstr_standard tap *
  page80_i44
#ISCELL
  mstr_standard tap *
  page80_i45
#ISCELL
  mstr_standard tap *
  page80_i46
#ISCELL
  mstr_standard tap *
  page80_i47
#ISCELL
  mstr_standard tap *
  page80_i48
#ISCELL
  mstr_standard tap *
  page80_i49
#ISCELL
  mstr_standard offpage *
  page80_i5
#ISCELL
  mstr_standard tap *
  page80_i50
#ISCELL
  mstr_standard tap *
  page80_i51
#ISCELL
  mstr_standard tap *
  page80_i52
#ISCELL
  mstr_standard tap *
  page80_i53
#ISCELL
  mstr_standard tap *
  page80_i54
#ISCELL
  mstr_standard tap *
  page80_i55
#CELL
  mstr_sconn sconn288_h44441003 *
  page80_i56
#ISCELL
  mstr_standard tap *
  page80_i57
#ISCELL
  mstr_standard tap *
  page80_i58
#ISCELL
  mstr_standard tap *
  page80_i59
#ISCELL
  mstr_standard offpage *
  page80_i6
#ISCELL
  mstr_standard tap *
  page80_i60
#ISCELL
  mstr_standard tap *
  page80_i61
#ISCELL
  mstr_standard tap *
  page80_i62
#ISCELL
  mstr_standard tap *
  page80_i63
#ISCELL
  mstr_standard tap *
  page80_i64
#ISCELL
  mstr_standard tap *
  page80_i65
#ISCELL
  mstr_standard tap *
  page80_i66
#ISCELL
  mstr_standard tap *
  page80_i67
#ISCELL
  mstr_standard tap *
  page80_i68
#ISCELL
  mstr_standard tap *
  page80_i69
#ISCELL
  mstr_standard offpage *
  page80_i7
#ISCELL
  mstr_standard tap *
  page80_i70
#ISCELL
  mstr_standard tap *
  page80_i71
#ISCELL
  mstr_standard tap *
  page80_i72
#ISCELL
  mstr_standard tap *
  page80_i73
#ISCELL
  mstr_standard tap *
  page80_i74
#ISCELL
  mstr_standard tap *
  page80_i75
#ISCELL
  mstr_standard tap *
  page80_i76
#ISCELL
  mstr_standard tap *
  page80_i77
#ISCELL
  mstr_symbols pvddq_ghj *
  page80_i78
#ISCELL
  mstr_symbols pvtt_ghj *
  page80_i79
#ISCELL
  mstr_symbols pvpp_ghj *
  page80_i8
#ISCELL
  mstr_symbols pvpp_ghj *
  page80_i80
#ISCELL
  mstr_standard tap *
  page80_i81
#ISCELL
  mstr_standard tap *
  page80_i82
#ISCELL
  mstr_standard tap *
  page80_i83
#ISCELL
  mstr_standard tap *
  page80_i84
#ISCELL
  mstr_standard tap *
  page80_i85
#ISCELL
  mstr_standard tap *
  page80_i86
#ISCELL
  mstr_standard tap *
  page80_i87
#ISCELL
  mstr_standard tap *
  page80_i88
#ISCELL
  mstr_standard tap *
  page80_i89
#ISCELL
  mstr_standard offpage *
  page80_i9
#ISCELL
  mstr_standard tap *
  page80_i90
#ISCELL
  mstr_standard tap *
  page80_i91
#ISCELL
  mstr_standard tap *
  page80_i92
#ISCELL
  mstr_standard tap *
  page80_i93
#ISCELL
  mstr_standard tap *
  page80_i94
#ISCELL
  mstr_standard tap *
  page80_i95
#ISCELL
  mstr_standard tap *
  page80_i96
#ISCELL
  mstr_standard tap *
  page80_i97
#ISCELL
  mstr_standard tap *
  page80_i98
#ISCELL
  mstr_standard tap *
  page80_i99
